# BASEBOARD_FAB2 (Tioga Pass) — schematic netlist excerpt (pin names and nets, part order shuffled) for the footprints in the layout excerpt that follows; sources: Cadence DE-HDL packaged netlist, KiCad conversion of Wiwynn_Tioga_Pass_MB.brd

R7F12  RES  0.0 5% CHIP  pkg 0402  page 231 : A = PVPP_ABC ; B = VSENSE_PVPP_ABC
R1G3  RES  1.00K 1% CHIP  pkg 0402  page 100 : A = M_H_VREF ; B = GND
C8C1  CAP  33.0PF 50V 5% COG  pkg 0402LF  page 118 : A = XTAL_KR_25M_IN ; B = GND

(kicad_pcb
	(version 20260206)
	(generator "pcbnew")
	(generator_version "10.0")
	(general
		(thickness 1.6)
		(legacy_teardrops no)
	)
	(paper "A4")
	(title_block
		(title "Wiwynn_Tioga_Pass_MB.brd")
		(comment 1 "Tioga Pass / footprints 1229-1231 of 4770")
	)
	(layers
		(0 "F.Cu" signal "TOP")
		(4 "In1.Cu" signal "L2GND")
		(6 "In2.Cu" signal "L3")
		(8 "In3.Cu" signal "L4GND")
		(10 "In4.Cu" signal "L5")
		(12 "In5.Cu" signal "L6GND")
		(14 "In6.Cu" signal "L7VCC")
		(16 "In7.Cu" signal "L8VCC")
		(18 "In8.Cu" signal "L9GND")
		(20 "In9.Cu" signal "L10")
		(22 "In10.Cu" signal "L11GND")
		(24 "In11.Cu" signal "L12")
		(26 "In12.Cu" signal "L13GND")
		(2 "B.Cu" signal "BOTTOM")
		(9 "F.Adhes" user "F.Adhesive")
		(11 "B.Adhes" user "B.Adhesive")
		(13 "F.Paste" user "Package Geometry/Pastemask Top")
		(15 "B.Paste" user "Package Geometry/Pastemask Bottom")
		(5 "F.SilkS" user "Ref Des/Silkscreen Top")
		(7 "B.SilkS" user "Ref Des/Silkscreen Bottom")
		(1 "F.Mask" user "Board Geometry/Soldermask Top")
		(3 "B.Mask" user "Board Geometry/Soldermask Bottom")
		(17 "Dwgs.User" user "User.Drawings")
		(19 "Cmts.User" user "User.Comments")
		(21 "Eco1.User" user "User.Eco1")
		(23 "Eco2.User" user "User.Eco2")
		(25 "Edge.Cuts" user "Board Geometry/Outline")
		(27 "Margin" user)
		(31 "F.CrtYd" user "Package Geometry/Place Bound Top")
		(29 "B.CrtYd" user "Package Geometry/Place Bound Bottom")
		(35 "F.Fab" user "Ref Des/Assembly Top")
		(33 "B.Fab" user "Ref Des/Assembly Bottom")
	)
	(footprint ""
		(layer "F.Cu")
		(at 404.990554 -100.337112 180)
		(property "Reference" "C8C1"
			(at 0 0 180)
			(layer "F.SilkS")
			(hide yes)
			(effects
				(font
					(size 1.27 1.27)
				)
			)
		)
		(property "Value" ""
			(at 0 0 180)
			(layer "F.Fab")
			(effects
				(font
					(size 1.27 1.27)
				)
			)
		)
		(duplicate_pad_numbers_are_jumpers no)
		(fp_poly
			(pts
				(xy 0.3048 -0.1016) (xy 0.3048 0.9906) (xy -0.3048 0.9906) (xy -0.3048 -0.1016)
			)
			(stroke
				(width 0)
				(type default)
			)
			(fill no)
			(layer "F.CrtYd")
		)
		(fp_line
			(start 0.3048 0.9906)
			(end 0.3048 -0.1016)
			(stroke
				(width 0.1)
				(type default)
			)
			(layer "F.Fab")
		)
		(fp_line
			(start 0.3048 -0.1016)
			(end -0.3048 -0.1016)
			(stroke
				(width 0.1)
				(type default)
			)
			(layer "F.Fab")
		)
		(fp_line
			(start -0.3048 0.9906)
			(end 0.3048 0.9906)
			(stroke
				(width 0.1)
				(type default)
			)
			(layer "F.Fab")
		)
		(fp_line
			(start -0.3048 -0.1016)
			(end -0.3048 0.9906)
			(stroke
				(width 0.1)
				(type default)
			)
			(layer "F.Fab")
		)
		(pad "1" smd rect
			(at 0 0 180)
			(size 0.508 0.508)
			(layers "F.Cu" "F.Mask" "F.Paste")
			(net "XTAL_KR_25M_IN")
		)
		(pad "2" smd rect
			(at 0 0.889 180)
			(size 0.508 0.508)
			(layers "F.Cu" "F.Mask" "F.Paste")
			(net "GND")
		)
		(zone
			(layer "F.Cu")
			(hatch none 0.5)
			(connect_pads
				(clearance 0)
			)
			(min_thickness 0.25)
			(keepout
				(tracks not_allowed)
				(vias allowed)
				(pads allowed)
				(copperpour not_allowed)
				(footprints allowed)
			)
			(placement
				(enabled no)
				(sheetname "")
			)
			(fill
				(thermal_gap 0.5)
				(thermal_bridge_width 0.5)
				(island_removal_mode 0)
			)
			(polygon
				(pts
					(xy 405.244554 -100.972112) (xy 404.736554 -100.972112) (xy 404.736554 -100.591112) (xy 405.244554 -100.591112)
				)
			)
		)
		(zone
			(layer "F.Cu")
			(hatch none 0.5)
			(connect_pads
				(clearance 0)
			)
			(min_thickness 0.25)
			(keepout
				(tracks allowed)
				(vias not_allowed)
				(pads allowed)
				(copperpour not_allowed)
				(footprints allowed)
			)
			(placement
				(enabled no)
				(sheetname "")
			)
			(fill
				(thermal_gap 0.5)
				(thermal_bridge_width 0.5)
				(island_removal_mode 0)
			)
			(polygon
				(pts
					(xy 405.244554 -100.591112) (xy 404.736554 -100.591112) (xy 404.736554 -100.972112) (xy 405.244554 -100.972112)
				)
			)
		)
	)
	(footprint ""
		(layer "F.Cu")
		(at 334.137 -24.13 90)
		(property "Reference" "R7F12"
			(at 0 0 90)
			(layer "F.SilkS")
			(hide yes)
			(effects
				(font
					(size 1.27 1.27)
				)
			)
		)
		(property "Value" ""
			(at 0 0 90)
			(layer "F.Fab")
			(effects
				(font
					(size 1.27 1.27)
				)
			)
		)
		(duplicate_pad_numbers_are_jumpers no)
		(fp_rect
			(start 0.2794 0.9906)
			(end -0.2794 -0.1016)
			(stroke
				(width 0)
				(type default)
			)
			(fill no)
			(layer "F.CrtYd")
		)
		(fp_line
			(start 0.2794 -0.1016)
			(end -0.2794 -0.1016)
			(stroke
				(width 0.1)
				(type default)
			)
			(layer "F.Fab")
		)
		(fp_line
			(start -0.2794 -0.1016)
			(end -0.2794 0.9906)
			(stroke
				(width 0.1)
				(type default)
			)
			(layer "F.Fab")
		)
		(fp_line
			(start 0.2794 0.9906)
			(end 0.2794 -0.1016)
			(stroke
				(width 0.1)
				(type default)
			)
			(layer "F.Fab")
		)
		(fp_line
			(start -0.2794 0.9906)
			(end 0.2794 0.9906)
			(stroke
				(width 0.1)
				(type default)
			)
			(layer "F.Fab")
		)
		(pad "1" smd rect
			(at 0 0 90)
			(size 0.508 0.508)
			(layers "F.Cu" "F.Mask" "F.Paste")
			(net "PVPP_ABC")
		)
		(pad "2" smd rect
			(at 0 0.889 90)
			(size 0.508 0.508)
			(layers "F.Cu" "F.Mask" "F.Paste")
			(net "VSENSE_PVPP_ABC")
		)
		(zone
			(layer "F.Cu")
			(hatch none 0.5)
			(connect_pads
				(clearance 0)
			)
			(min_thickness 0.25)
			(keepout
				(tracks not_allowed)
				(vias allowed)
				(pads allowed)
				(copperpour not_allowed)
				(footprints allowed)
			)
			(placement
				(enabled no)
				(sheetname "")
			)
			(fill
				(thermal_gap 0.5)
				(thermal_bridge_width 0.5)
				(island_removal_mode 0)
			)
			(polygon
				(pts
					(xy 334.772 -24.384) (xy 334.391 -24.384) (xy 334.391 -23.876) (xy 334.772 -23.876)
				)
			)
		)
		(zone
			(layer "F.Cu")
			(hatch none 0.5)
			(connect_pads
				(clearance 0)
			)
			(min_thickness 0.25)
			(keepout
				(tracks allowed)
				(vias not_allowed)
				(pads allowed)
				(copperpour not_allowed)
				(footprints allowed)
			)
			(placement
				(enabled no)
				(sheetname "")
			)
			(fill
				(thermal_gap 0.5)
				(thermal_bridge_width 0.5)
				(island_removal_mode 0)
			)
			(polygon
				(pts
					(xy 334.772 -24.384) (xy 334.391 -24.384) (xy 334.391 -23.876) (xy 334.772 -23.876)
				)
			)
		)
	)
	(footprint ""
		(layer "F.Cu")
		(at 29.464 -12.4841 180)
		(property "Reference" "R1G3"
			(at 0 0 180)
			(layer "F.SilkS")
			(hide yes)
			(effects
				(font
					(size 1.27 1.27)
				)
			)
		)
		(property "Value" ""
			(at 0 0 180)
			(layer "F.Fab")
			(effects
				(font
					(size 1.27 1.27)
				)
			)
		)
		(duplicate_pad_numbers_are_jumpers no)
		(fp_poly
			(pts
				(xy -0.2794 -0.1016) (xy 0.2794 -0.1016) (xy 0.2794 0.9906) (xy -0.2794 0.9906)
			)
			(stroke
				(width 0)
				(type default)
			)
			(fill no)
			(layer "F.CrtYd")
		)
		(fp_line
			(start 0.2794 0.9906)
			(end 0.2794 -0.1016)
			(stroke
				(width 0.1)
				(type default)
			)
			(layer "F.Fab")
		)
		(fp_line
			(start 0.2794 -0.1016)
			(end -0.2794 -0.1016)
			(stroke
				(width 0.1)
				(type default)
			)
			(layer "F.Fab")
		)
		(fp_line
			(start -0.2794 0.9906)
			(end 0.2794 0.9906)
			(stroke
				(width 0.1)
				(type default)
			)
			(layer "F.Fab")
		)
		(fp_line
			(start -0.2794 -0.1016)
			(end -0.2794 0.9906)
			(stroke
				(width 0.1)
				(type default)
			)
			(layer "F.Fab")
		)
		(pad "1" smd rect
			(at 0 0 180)
			(size 0.508 0.508)
			(layers "F.Cu" "F.Mask" "F.Paste")
			(net "M_H_VREF")
		)
		(pad "2" smd rect
			(at 0 0.889 180)
			(size 0.508 0.508)
			(layers "F.Cu" "F.Mask" "F.Paste")
			(net "GND")
		)
		(zone
			(layer "F.Cu")
			(hatch none 0.5)
			(connect_pads
				(clearance 0)
			)
			(min_thickness 0.25)
			(keepout
				(tracks not_allowed)
				(vias allowed)
				(pads allowed)
				(copperpour not_allowed)
				(footprints allowed)
			)
			(placement
				(enabled no)
				(sheetname "")
			)
			(fill
				(thermal_gap 0.5)
				(thermal_bridge_width 0.5)
				(island_removal_mode 0)
			)
			(polygon
				(pts
					(xy 29.718 -13.1191) (xy 29.21 -13.1191) (xy 29.21 -12.7381) (xy 29.718 -12.7381)
				)
			)
		)
		(zone
			(layer "F.Cu")
			(hatch none 0.5)
			(connect_pads
				(clearance 0)
			)
			(min_thickness 0.25)
			(keepout
				(tracks allowed)
				(vias not_allowed)
				(pads allowed)
				(copperpour not_allowed)
				(footprints allowed)
			)
			(placement
				(enabled no)
				(sheetname "")
			)
			(fill
				(thermal_gap 0.5)
				(thermal_bridge_width 0.5)
				(island_removal_mode 0)
			)
			(polygon
				(pts
					(xy 29.718 -12.7381) (xy 29.21 -12.7381) (xy 29.21 -13.1191) (xy 29.718 -13.1191)
				)
			)
		)
	)
)
